# S9S_MB_2U (Grand Teton) — schematic netlist excerpt (pin names and nets, part order shuffled) for the footprints in the layout excerpt that follows; sources: Cadence DE-HDL packaged netlist, KiCad conversion of 03242023_DA0F0TMBIJ0_F0T_Motherboard_J_brd_V01_OCP.brd

H87  HOLE  EMPTY  pkg TH  page 311 : \1\ = GND
PR3921  Q_RES  0 5% CHIP  pkg 0402LF  page 302 : A = HSC_D_OC_2 ; B = HSC_D_OC_R
D70  Q_LED  IC  pkg SMLF  page 256 : A = LED_RST_PLD_CPU1_DRAM_CD_N ; C = LED_RST_PLD_CPU1_DRAM_CD_N_D

(kicad_pcb
	(version 20260206)
	(generator "pcbnew")
	(generator_version "10.0")
	(general
		(thickness 1.6)
		(legacy_teardrops no)
	)
	(paper "A4")
	(title_block
		(title "03242023_DA0F0TMBIJ0_F0T_Motherboard_J_brd_V01_OCP.brd")
		(comment 1 "Grand Teton / footprints 2324-2326 of 6105")
	)
	(layers
		(0 "F.Cu" signal "TOP")
		(4 "In1.Cu" signal "GND")
		(6 "In2.Cu" signal "IN1")
		(8 "In3.Cu" signal "GND1")
		(10 "In4.Cu" signal "IN2")
		(12 "In5.Cu" signal "GND2")
		(14 "In6.Cu" signal "IN3")
		(16 "In7.Cu" signal "GND3")
		(18 "In8.Cu" signal "VCC")
		(20 "In9.Cu" signal "VCC1")
		(22 "In10.Cu" signal "GND4")
		(24 "In11.Cu" signal "IN4")
		(26 "In12.Cu" signal "GND5")
		(28 "In13.Cu" signal "IN5")
		(30 "In14.Cu" signal "GND6")
		(32 "In15.Cu" signal "IN6")
		(34 "In16.Cu" signal "GND7")
		(2 "B.Cu" signal "BOTTOM")
		(9 "F.Adhes" user "F.Adhesive")
		(11 "B.Adhes" user "B.Adhesive")
		(13 "F.Paste" user "Package Geometry/Pastemask Top")
		(15 "B.Paste" user "Package Geometry/Pastemask Bottom")
		(5 "F.SilkS" user "Ref Des/Silkscreen Top")
		(7 "B.SilkS" user "Ref Des/Silkscreen Bottom")
		(1 "F.Mask" user "Board Geometry/Soldermask Top")
		(3 "B.Mask" user "Board Geometry/Soldermask Bottom")
		(17 "Dwgs.User" user "User.Drawings")
		(19 "Cmts.User" user "User.Comments")
		(21 "Eco1.User" user "User.Eco1")
		(23 "Eco2.User" user "User.Eco2")
		(25 "Edge.Cuts" user "Board Geometry/Outline")
		(27 "Margin" user)
		(31 "F.CrtYd" user "Package Geometry/Place Bound Top")
		(29 "B.CrtYd" user "Package Geometry/Place Bound Bottom")
		(35 "F.Fab" user "Ref Des/Assembly Top")
		(33 "B.Fab" user "Ref Des/Assembly Bottom")
	)
	(footprint ""
		(layer "F.Cu")
		(at 64.979296 -70.78599)
		(property "Reference" "D70"
			(at -34.630106 50.178462 90)
			(unlocked yes)
			(layer "F.SilkS")
			(effects
				(font
					(size 0.635 0.4064)
					(thickness 0.1524)
				)
				(justify left)
			)
		)
		(property "Value" ""
			(at 0 0 0)
			(layer "F.Fab")
			(effects
				(font
					(size 1.27 1.27)
				)
			)
		)
		(duplicate_pad_numbers_are_jumpers no)
		(fp_line
			(start -0.90678 0.4826)
			(end -0.90678 -0.4699)
			(stroke
				(width 0.1524)
				(type default)
			)
			(layer "F.SilkS")
		)
		(fp_line
			(start -0.89408 -0.4826)
			(end 0.90678 -0.4826)
			(stroke
				(width 0.1524)
				(type default)
			)
			(layer "F.SilkS")
		)
		(fp_line
			(start -0.79248 -0.4826)
			(end 1.03378 -0.4826)
			(stroke
				(width 0.1524)
				(type default)
			)
			(layer "F.SilkS")
		)
		(fp_line
			(start -0.64008 -0.4826)
			(end 1.16078 -0.4826)
			(stroke
				(width 0.1524)
				(type default)
			)
			(layer "F.SilkS")
		)
		(fp_line
			(start 0.90678 -0.4826)
			(end 0.90678 0.4826)
			(stroke
				(width 0.1524)
				(type default)
			)
			(layer "F.SilkS")
		)
		(fp_line
			(start 0.90678 0.4826)
			(end -0.90678 0.4826)
			(stroke
				(width 0.1524)
				(type default)
			)
			(layer "F.SilkS")
		)
		(fp_line
			(start 1.03378 -0.4826)
			(end 1.03378 0.4826)
			(stroke
				(width 0.1524)
				(type default)
			)
			(layer "F.SilkS")
		)
		(fp_line
			(start 1.03378 0.4826)
			(end -0.79248 0.4826)
			(stroke
				(width 0.1524)
				(type default)
			)
			(layer "F.SilkS")
		)
		(fp_line
			(start 1.16078 -0.4826)
			(end 1.16078 0.4826)
			(stroke
				(width 0.1524)
				(type default)
			)
			(layer "F.SilkS")
		)
		(fp_line
			(start 1.16078 0.4826)
			(end -0.64008 0.4826)
			(stroke
				(width 0.1524)
				(type default)
			)
			(layer "F.SilkS")
		)
		(fp_line
			(start -0.499872 -0.249936)
			(end 0.499872 -0.249936)
			(stroke
				(width 0.1)
				(type default)
			)
			(layer "F.Fab")
		)
		(fp_line
			(start -0.499872 0.249936)
			(end -0.499872 -0.249936)
			(stroke
				(width 0.1)
				(type default)
			)
			(layer "F.Fab")
		)
		(fp_line
			(start 0.499872 -0.249936)
			(end 0.499872 0.249936)
			(stroke
				(width 0.1)
				(type default)
			)
			(layer "F.Fab")
		)
		(fp_line
			(start 0.499872 0.249936)
			(end -0.499872 0.249936)
			(stroke
				(width 0.1)
				(type default)
			)
			(layer "F.Fab")
		)
		(pad "A" smd rect
			(at -0.47498 0)
			(size 0.6096 0.7112)
			(layers "F.Cu" "F.Mask" "F.Paste")
			(net "LED_RST_PLD_CPU1_DRAM_CD_N")
		)
		(pad "C" smd rect
			(at 0.47498 0)
			(size 0.6096 0.7112)
			(layers "F.Cu" "F.Mask" "F.Paste")
			(net "LED_RST_PLD_CPU1_DRAM_CD_N_D")
		)
	)
	(footprint ""
		(layer "F.Cu")
		(at 216.065608 -400.759422)
		(property "Reference" "PR3921"
			(at 0 0 0)
			(layer "F.SilkS")
			(hide yes)
			(effects
				(font
					(size 1.27 1.27)
				)
			)
		)
		(property "Value" ""
			(at 0 0 0)
			(layer "F.Fab")
			(effects
				(font
					(size 1.27 1.27)
				)
			)
		)
		(duplicate_pad_numbers_are_jumpers no)
		(fp_line
			(start -0.7874 -0.4064)
			(end 0.7874 -0.4064)
			(stroke
				(width 0.1524)
				(type default)
			)
			(layer "F.SilkS")
		)
		(fp_line
			(start -0.7874 0.4064)
			(end -0.7874 -0.4064)
			(stroke
				(width 0.1524)
				(type default)
			)
			(layer "F.SilkS")
		)
		(fp_line
			(start 0.7874 -0.4064)
			(end 0.7874 0.4064)
			(stroke
				(width 0.1524)
				(type default)
			)
			(layer "F.SilkS")
		)
		(fp_line
			(start 0.7874 0.4064)
			(end -0.7874 0.4064)
			(stroke
				(width 0.1524)
				(type default)
			)
			(layer "F.SilkS")
		)
		(fp_line
			(start -0.67945 -0.305054)
			(end -0.12065 -0.305054)
			(stroke
				(width 0.1)
				(type default)
			)
			(layer "F.Fab")
		)
		(fp_line
			(start -0.67945 0.3048)
			(end -0.67945 -0.305054)
			(stroke
				(width 0.1)
				(type default)
			)
			(layer "F.Fab")
		)
		(fp_line
			(start -0.12065 -0.305054)
			(end -0.12065 -0.2794)
			(stroke
				(width 0.1)
				(type default)
			)
			(layer "F.Fab")
		)
		(fp_line
			(start -0.12065 -0.2794)
			(end 0.12065 -0.2794)
			(stroke
				(width 0.1)
				(type default)
			)
			(layer "F.Fab")
		)
		(fp_line
			(start -0.12065 0.2794)
			(end -0.12065 0.3048)
			(stroke
				(width 0.1)
				(type default)
			)
			(layer "F.Fab")
		)
		(fp_line
			(start -0.12065 0.3048)
			(end -0.67945 0.3048)
			(stroke
				(width 0.1)
				(type default)
			)
			(layer "F.Fab")
		)
		(fp_line
			(start 0.120396 0.2794)
			(end -0.12065 0.2794)
			(stroke
				(width 0.1)
				(type default)
			)
			(layer "F.Fab")
		)
		(fp_line
			(start 0.120396 0.3048)
			(end 0.120396 0.2794)
			(stroke
				(width 0.1)
				(type default)
			)
			(layer "F.Fab")
		)
		(fp_line
			(start 0.12065 -0.3048)
			(end 0.67945 -0.3048)
			(stroke
				(width 0.1)
				(type default)
			)
			(layer "F.Fab")
		)
		(fp_line
			(start 0.12065 -0.2794)
			(end 0.12065 -0.3048)
			(stroke
				(width 0.1)
				(type default)
			)
			(layer "F.Fab")
		)
		(fp_line
			(start 0.67945 -0.3048)
			(end 0.67945 0.3048)
			(stroke
				(width 0.1)
				(type default)
			)
			(layer "F.Fab")
		)
		(fp_line
			(start 0.67945 0.3048)
			(end 0.120396 0.3048)
			(stroke
				(width 0.1)
				(type default)
			)
			(layer "F.Fab")
		)
		(pad "1" smd circle
			(at -0.40005 0)
			(size 0 0)
			(layers "F.Cu" "F.Mask" "F.Paste")
			(net "HSC_D_OC_2")
		)
		(pad "2" smd circle
			(at 0.40005 0)
			(size 0 0)
			(layers "F.Cu" "F.Mask" "F.Paste")
			(net "HSC_D_OC_R")
		)
	)
	(footprint ""
		(layer "F.Cu")
		(at 458.799946 -435.600094)
		(property "Reference" "H87"
			(at -5.13588 -4.694428 0)
			(unlocked yes)
			(layer "F.SilkS")
			(effects
				(font
					(size 0.7874 0.5842)
					(thickness 0.1524)
				)
				(justify left)
			)
		)
		(property "Value" ""
			(at 0 0 0)
			(layer "F.Fab")
			(effects
				(font
					(size 1.27 1.27)
				)
			)
		)
		(duplicate_pad_numbers_are_jumpers no)
		(pad "1" thru_hole circle
			(at 0 0)
			(size 10.0076 10.0076)
			(drill 5.6134)
			(layers "*.Cu" "*.Mask")
			(remove_unused_layers no)
			(net "GND")
			(clearance -1.9431)
		)
	)
)
